# S9S_MB_2U (Grand Teton) — schematic netlist excerpt (pin names and nets, part order shuffled) for the footprints in the layout excerpt that follows; sources: Cadence DE-HDL packaged netlist, KiCad conversion of 03242023_DA0F0TMBIJ0_F0T_Motherboard_J_brd_V01_OCP.brd

R2252  Q_RES  100K 1% EMPTY  pkg 0402LF  page 197 : A = PECI_MUX_SEL_R ; B = GND
R3468  Q_RES  49.9 1% CHIP  pkg 0402LF  page 149 : A = RST_PERST_2_SWB_BUF_R_N ; B = RST_PERST_2_SWB_BUF_N

(kicad_pcb
	(version 20260206)
	(generator "pcbnew")
	(generator_version "10.0")
	(general
		(thickness 1.6)
		(legacy_teardrops no)
	)
	(paper "A4")
	(title_block
		(title "03242023_DA0F0TMBIJ0_F0T_Motherboard_J_brd_V01_OCP.brd")
		(comment 1 "Grand Teton / footprints 2024-2025 of 6105")
	)
	(layers
		(0 "F.Cu" signal "TOP")
		(4 "In1.Cu" signal "GND")
		(6 "In2.Cu" signal "IN1")
		(8 "In3.Cu" signal "GND1")
		(10 "In4.Cu" signal "IN2")
		(12 "In5.Cu" signal "GND2")
		(14 "In6.Cu" signal "IN3")
		(16 "In7.Cu" signal "GND3")
		(18 "In8.Cu" signal "VCC")
		(20 "In9.Cu" signal "VCC1")
		(22 "In10.Cu" signal "GND4")
		(24 "In11.Cu" signal "IN4")
		(26 "In12.Cu" signal "GND5")
		(28 "In13.Cu" signal "IN5")
		(30 "In14.Cu" signal "GND6")
		(32 "In15.Cu" signal "IN6")
		(34 "In16.Cu" signal "GND7")
		(2 "B.Cu" signal "BOTTOM")
		(9 "F.Adhes" user "F.Adhesive")
		(11 "B.Adhes" user "B.Adhesive")
		(13 "F.Paste" user "Package Geometry/Pastemask Top")
		(15 "B.Paste" user "Package Geometry/Pastemask Bottom")
		(5 "F.SilkS" user "Ref Des/Silkscreen Top")
		(7 "B.SilkS" user "Ref Des/Silkscreen Bottom")
		(1 "F.Mask" user "Board Geometry/Soldermask Top")
		(3 "B.Mask" user "Board Geometry/Soldermask Bottom")
		(17 "Dwgs.User" user "User.Drawings")
		(19 "Cmts.User" user "User.Comments")
		(21 "Eco1.User" user "User.Eco1")
		(23 "Eco2.User" user "User.Eco2")
		(25 "Edge.Cuts" user "Board Geometry/Outline")
		(27 "Margin" user)
		(31 "F.CrtYd" user "Package Geometry/Place Bound Top")
		(29 "B.CrtYd" user "Package Geometry/Place Bound Bottom")
		(35 "F.Fab" user "Ref Des/Assembly Top")
		(33 "B.Fab" user "Ref Des/Assembly Bottom")
	)
	(footprint ""
		(layer "F.Cu")
		(at 304.53965 -61.130688 180)
		(property "Reference" "R2252"
			(at 0 0 180)
			(layer "F.SilkS")
			(hide yes)
			(effects
				(font
					(size 1.27 1.27)
				)
			)
		)
		(property "Value" ""
			(at 0 0 180)
			(layer "F.Fab")
			(effects
				(font
					(size 1.27 1.27)
				)
			)
		)
		(duplicate_pad_numbers_are_jumpers no)
		(fp_line
			(start 0.7874 0.4064)
			(end -0.7874 0.4064)
			(stroke
				(width 0.1524)
				(type default)
			)
			(layer "F.SilkS")
		)
		(fp_line
			(start 0.7874 -0.4064)
			(end 0.7874 0.4064)
			(stroke
				(width 0.1524)
				(type default)
			)
			(layer "F.SilkS")
		)
		(fp_line
			(start -0.7874 0.4064)
			(end -0.7874 -0.4064)
			(stroke
				(width 0.1524)
				(type default)
			)
			(layer "F.SilkS")
		)
		(fp_line
			(start -0.7874 -0.4064)
			(end 0.7874 -0.4064)
			(stroke
				(width 0.1524)
				(type default)
			)
			(layer "F.SilkS")
		)
		(fp_line
			(start 0.67945 0.3048)
			(end 0.120396 0.3048)
			(stroke
				(width 0.1)
				(type default)
			)
			(layer "F.Fab")
		)
		(fp_line
			(start 0.67945 -0.3048)
			(end 0.67945 0.3048)
			(stroke
				(width 0.1)
				(type default)
			)
			(layer "F.Fab")
		)
		(fp_line
			(start 0.12065 -0.2794)
			(end 0.12065 -0.3048)
			(stroke
				(width 0.1)
				(type default)
			)
			(layer "F.Fab")
		)
		(fp_line
			(start 0.12065 -0.3048)
			(end 0.67945 -0.3048)
			(stroke
				(width 0.1)
				(type default)
			)
			(layer "F.Fab")
		)
		(fp_line
			(start 0.120396 0.3048)
			(end 0.120396 0.2794)
			(stroke
				(width 0.1)
				(type default)
			)
			(layer "F.Fab")
		)
		(fp_line
			(start 0.120396 0.2794)
			(end -0.12065 0.2794)
			(stroke
				(width 0.1)
				(type default)
			)
			(layer "F.Fab")
		)
		(fp_line
			(start -0.12065 0.3048)
			(end -0.67945 0.3048)
			(stroke
				(width 0.1)
				(type default)
			)
			(layer "F.Fab")
		)
		(fp_line
			(start -0.12065 0.2794)
			(end -0.12065 0.3048)
			(stroke
				(width 0.1)
				(type default)
			)
			(layer "F.Fab")
		)
		(fp_line
			(start -0.12065 -0.2794)
			(end 0.12065 -0.2794)
			(stroke
				(width 0.1)
				(type default)
			)
			(layer "F.Fab")
		)
		(fp_line
			(start -0.12065 -0.305054)
			(end -0.12065 -0.2794)
			(stroke
				(width 0.1)
				(type default)
			)
			(layer "F.Fab")
		)
		(fp_line
			(start -0.67945 0.3048)
			(end -0.67945 -0.305054)
			(stroke
				(width 0.1)
				(type default)
			)
			(layer "F.Fab")
		)
		(fp_line
			(start -0.67945 -0.305054)
			(end -0.12065 -0.305054)
			(stroke
				(width 0.1)
				(type default)
			)
			(layer "F.Fab")
		)
		(pad "1" smd circle
			(at -0.40005 0 180)
			(size 0 0)
			(layers "F.Cu" "F.Mask" "F.Paste")
			(net "PECI_MUX_SEL_R")
		)
		(pad "2" smd circle
			(at 0.40005 0 180)
			(size 0 0)
			(layers "F.Cu" "F.Mask" "F.Paste")
			(net "GND")
		)
	)
	(footprint ""
		(layer "F.Cu")
		(at 31.29788 -432.907948)
		(property "Reference" "R3468"
			(at 0 0 0)
			(layer "F.SilkS")
			(hide yes)
			(effects
				(font
					(size 1.27 1.27)
				)
			)
		)
		(property "Value" ""
			(at 0 0 0)
			(layer "F.Fab")
			(effects
				(font
					(size 1.27 1.27)
				)
			)
		)
		(duplicate_pad_numbers_are_jumpers no)
		(fp_line
			(start -0.7874 -0.4064)
			(end 0.7874 -0.4064)
			(stroke
				(width 0.1524)
				(type default)
			)
			(layer "F.SilkS")
		)
		(fp_line
			(start -0.7874 0.4064)
			(end -0.7874 -0.4064)
			(stroke
				(width 0.1524)
				(type default)
			)
			(layer "F.SilkS")
		)
		(fp_line
			(start 0.7874 -0.4064)
			(end 0.7874 0.4064)
			(stroke
				(width 0.1524)
				(type default)
			)
			(layer "F.SilkS")
		)
		(fp_line
			(start 0.7874 0.4064)
			(end -0.7874 0.4064)
			(stroke
				(width 0.1524)
				(type default)
			)
			(layer "F.SilkS")
		)
		(fp_line
			(start -0.67945 -0.305054)
			(end -0.12065 -0.305054)
			(stroke
				(width 0.1)
				(type default)
			)
			(layer "F.Fab")
		)
		(fp_line
			(start -0.67945 0.3048)
			(end -0.67945 -0.305054)
			(stroke
				(width 0.1)
				(type default)
			)
			(layer "F.Fab")
		)
		(fp_line
			(start -0.12065 -0.305054)
			(end -0.12065 -0.2794)
			(stroke
				(width 0.1)
				(type default)
			)
			(layer "F.Fab")
		)
		(fp_line
			(start -0.12065 -0.2794)
			(end 0.12065 -0.2794)
			(stroke
				(width 0.1)
				(type default)
			)
			(layer "F.Fab")
		)
		(fp_line
			(start -0.12065 0.2794)
			(end -0.12065 0.3048)
			(stroke
				(width 0.1)
				(type default)
			)
			(layer "F.Fab")
		)
		(fp_line
			(start -0.12065 0.3048)
			(end -0.67945 0.3048)
			(stroke
				(width 0.1)
				(type default)
			)
			(layer "F.Fab")
		)
		(fp_line
			(start 0.120396 0.2794)
			(end -0.12065 0.2794)
			(stroke
				(width 0.1)
				(type default)
			)
			(layer "F.Fab")
		)
		(fp_line
			(start 0.120396 0.3048)
			(end 0.120396 0.2794)
			(stroke
				(width 0.1)
				(type default)
			)
			(layer "F.Fab")
		)
		(fp_line
			(start 0.12065 -0.3048)
			(end 0.67945 -0.3048)
			(stroke
				(width 0.1)
				(type default)
			)
			(layer "F.Fab")
		)
		(fp_line
			(start 0.12065 -0.2794)
			(end 0.12065 -0.3048)
			(stroke
				(width 0.1)
				(type default)
			)
			(layer "F.Fab")
		)
		(fp_line
			(start 0.67945 -0.3048)
			(end 0.67945 0.3048)
			(stroke
				(width 0.1)
				(type default)
			)
			(layer "F.Fab")
		)
		(fp_line
			(start 0.67945 0.3048)
			(end 0.120396 0.3048)
			(stroke
				(width 0.1)
				(type default)
			)
			(layer "F.Fab")
		)
		(pad "1" smd circle
			(at -0.40005 0)
			(size 0 0)
			(layers "F.Cu" "F.Mask" "F.Paste")
			(net "RST_PERST_2_SWB_BUF_R_N")
		)
		(pad "2" smd circle
			(at 0.40005 0)
			(size 0 0)
			(layers "F.Cu" "F.Mask" "F.Paste")
			(net "RST_PERST_2_SWB_BUF_N")
		)
	)
)
